# T6G (Grand Teton) — schematic netlist excerpt (pin names and nets, part order shuffled) for the footprints in the layout excerpt that follows; sources: Cadence DE-HDL packaged netlist, KiCad conversion of 04192023_DAF0TMB3IC0_F0TG_MB_C_brd_V02_OCP.brd

C482  Q_CAP  10UF 6.3V 20% X6S  pkg C0402  page 356 : A = P0V9_CPU1_RT3_2A ; B = GND
R776  Q_RES  35.7K 1% CHIP  pkg 0402LF  page 107 : A = PD_CHJ_CPU1_DIMM_SAA ; B = GND

(kicad_pcb
	(version 20260206)
	(generator "pcbnew")
	(generator_version "10.0")
	(general
		(thickness 1.6)
		(legacy_teardrops no)
	)
	(paper "A4")
	(title_block
		(title "04192023_DAF0TMB3IC0_F0TG_MB_C_brd_V02_OCP.brd")
		(comment 1 "Grand Teton / footprints 8233-8234 of 8354")
	)
	(layers
		(0 "F.Cu" signal "TOP")
		(4 "In1.Cu" signal "GND")
		(6 "In2.Cu" signal "IN1")
		(8 "In3.Cu" signal "GND1")
		(10 "In4.Cu" signal "IN2")
		(12 "In5.Cu" signal "GND2")
		(14 "In6.Cu" signal "IN3")
		(16 "In7.Cu" signal "GND3")
		(18 "In8.Cu" signal "VCC")
		(20 "In9.Cu" signal "VCC1")
		(22 "In10.Cu" signal "GND4")
		(24 "In11.Cu" signal "IN4")
		(26 "In12.Cu" signal "GND5")
		(28 "In13.Cu" signal "IN5")
		(30 "In14.Cu" signal "GND6")
		(32 "In15.Cu" signal "IN6")
		(34 "In16.Cu" signal "GND7")
		(2 "B.Cu" signal "BOTTOM")
		(9 "F.Adhes" user "F.Adhesive")
		(11 "B.Adhes" user "B.Adhesive")
		(13 "F.Paste" user "Package Geometry/Pastemask Top")
		(15 "B.Paste" user "Package Geometry/Pastemask Bottom")
		(5 "F.SilkS" user "Ref Des/Silkscreen Top")
		(7 "B.SilkS" user "Ref Des/Silkscreen Bottom")
		(1 "F.Mask" user "Board Geometry/Soldermask Top")
		(3 "B.Mask" user "Board Geometry/Soldermask Bottom")
		(17 "Dwgs.User" user "User.Drawings")
		(19 "Cmts.User" user "User.Comments")
		(21 "Eco1.User" user "User.Eco1")
		(23 "Eco2.User" user "User.Eco2")
		(25 "Edge.Cuts" user "Board Geometry/Outline")
		(27 "Margin" user)
		(31 "F.CrtYd" user "Package Geometry/Place Bound Top")
		(29 "B.CrtYd" user "Package Geometry/Place Bound Bottom")
		(35 "F.Fab" user "Ref Des/Assembly Top")
		(33 "B.Fab" user "Ref Des/Assembly Bottom")
	)
	(footprint ""
		(layer "B.Cu")
		(at 132.491226 -390.560052 90)
		(property "Reference" "C482"
			(at 0 0 90)
			(layer "B.SilkS")
			(hide yes)
			(effects
				(font
					(size 1.27 1.27)
				)
				(justify mirror)
			)
		)
		(property "Value" ""
			(at 0 0 90)
			(layer "B.Fab")
			(effects
				(font
					(size 1.27 1.27)
				)
				(justify mirror)
			)
		)
		(duplicate_pad_numbers_are_jumpers no)
		(fp_line
			(start 0.7874 -0.4064)
			(end -0.7874 -0.4064)
			(stroke
				(width 0.1524)
				(type default)
			)
			(layer "B.SilkS")
		)
		(fp_line
			(start -0.7874 -0.4064)
			(end -0.7874 0.4064)
			(stroke
				(width 0.1524)
				(type default)
			)
			(layer "B.SilkS")
		)
		(fp_line
			(start 0.7874 0.4064)
			(end 0.7874 -0.4064)
			(stroke
				(width 0.1524)
				(type default)
			)
			(layer "B.SilkS")
		)
		(fp_line
			(start -0.7874 0.4064)
			(end 0.7874 0.4064)
			(stroke
				(width 0.1524)
				(type default)
			)
			(layer "B.SilkS")
		)
		(fp_line
			(start 0.67945 -0.305054)
			(end 0.12065 -0.305054)
			(stroke
				(width 0.1)
				(type default)
			)
			(layer "B.Fab")
		)
		(fp_line
			(start 0.12065 -0.305054)
			(end 0.12065 -0.2794)
			(stroke
				(width 0.1)
				(type default)
			)
			(layer "B.Fab")
		)
		(fp_line
			(start -0.12065 -0.3048)
			(end -0.67945 -0.3048)
			(stroke
				(width 0.1)
				(type default)
			)
			(layer "B.Fab")
		)
		(fp_line
			(start -0.67945 -0.3048)
			(end -0.67945 0.3048)
			(stroke
				(width 0.1)
				(type default)
			)
			(layer "B.Fab")
		)
		(fp_line
			(start 0.12065 -0.2794)
			(end -0.12065 -0.2794)
			(stroke
				(width 0.1)
				(type default)
			)
			(layer "B.Fab")
		)
		(fp_line
			(start -0.12065 -0.2794)
			(end -0.12065 -0.3048)
			(stroke
				(width 0.1)
				(type default)
			)
			(layer "B.Fab")
		)
		(fp_line
			(start 0.12065 0.2794)
			(end 0.12065 0.3048)
			(stroke
				(width 0.1)
				(type default)
			)
			(layer "B.Fab")
		)
		(fp_line
			(start -0.120396 0.2794)
			(end 0.12065 0.2794)
			(stroke
				(width 0.1)
				(type default)
			)
			(layer "B.Fab")
		)
		(fp_line
			(start 0.67945 0.3048)
			(end 0.67945 -0.305054)
			(stroke
				(width 0.1)
				(type default)
			)
			(layer "B.Fab")
		)
		(fp_line
			(start 0.12065 0.3048)
			(end 0.67945 0.3048)
			(stroke
				(width 0.1)
				(type default)
			)
			(layer "B.Fab")
		)
		(fp_line
			(start -0.120396 0.3048)
			(end -0.120396 0.2794)
			(stroke
				(width 0.1)
				(type default)
			)
			(layer "B.Fab")
		)
		(fp_line
			(start -0.67945 0.3048)
			(end -0.120396 0.3048)
			(stroke
				(width 0.1)
				(type default)
			)
			(layer "B.Fab")
		)
		(pad "1" smd circle
			(at 0.40005 0 270)
			(size 0 0)
			(layers "B.Cu" "B.Mask" "B.Paste")
			(net "P0V9_CPU1_RT3_2A")
		)
		(pad "2" smd circle
			(at -0.40005 0 270)
			(size 0 0)
			(layers "B.Cu" "B.Mask" "B.Paste")
			(net "GND")
		)
	)
	(footprint ""
		(layer "B.Cu")
		(at 187.815728 -194.885564 180)
		(property "Reference" "R776"
			(at 0 0 0)
			(layer "B.SilkS")
			(hide yes)
			(effects
				(font
					(size 1.27 1.27)
				)
				(justify mirror)
			)
		)
		(property "Value" ""
			(at 0 0 0)
			(layer "B.Fab")
			(effects
				(font
					(size 1.27 1.27)
				)
				(justify mirror)
			)
		)
		(duplicate_pad_numbers_are_jumpers no)
		(fp_line
			(start 0.7874 0.4064)
			(end 0.7874 -0.4064)
			(stroke
				(width 0.1524)
				(type default)
			)
			(layer "B.SilkS")
		)
		(fp_line
			(start 0.7874 -0.4064)
			(end -0.7874 -0.4064)
			(stroke
				(width 0.1524)
				(type default)
			)
			(layer "B.SilkS")
		)
		(fp_line
			(start -0.7874 0.4064)
			(end 0.7874 0.4064)
			(stroke
				(width 0.1524)
				(type default)
			)
			(layer "B.SilkS")
		)
		(fp_line
			(start -0.7874 -0.4064)
			(end -0.7874 0.4064)
			(stroke
				(width 0.1524)
				(type default)
			)
			(layer "B.SilkS")
		)
		(fp_line
			(start 0.67945 0.3048)
			(end 0.67945 -0.305054)
			(stroke
				(width 0.1)
				(type default)
			)
			(layer "B.Fab")
		)
		(fp_line
			(start 0.67945 -0.305054)
			(end 0.12065 -0.305054)
			(stroke
				(width 0.1)
				(type default)
			)
			(layer "B.Fab")
		)
		(fp_line
			(start 0.12065 0.3048)
			(end 0.67945 0.3048)
			(stroke
				(width 0.1)
				(type default)
			)
			(layer "B.Fab")
		)
		(fp_line
			(start 0.12065 0.2794)
			(end 0.12065 0.3048)
			(stroke
				(width 0.1)
				(type default)
			)
			(layer "B.Fab")
		)
		(fp_line
			(start 0.12065 -0.2794)
			(end -0.12065 -0.2794)
			(stroke
				(width 0.1)
				(type default)
			)
			(layer "B.Fab")
		)
		(fp_line
			(start 0.12065 -0.305054)
			(end 0.12065 -0.2794)
			(stroke
				(width 0.1)
				(type default)
			)
			(layer "B.Fab")
		)
		(fp_line
			(start -0.120396 0.3048)
			(end -0.120396 0.2794)
			(stroke
				(width 0.1)
				(type default)
			)
			(layer "B.Fab")
		)
		(fp_line
			(start -0.120396 0.2794)
			(end 0.12065 0.2794)
			(stroke
				(width 0.1)
				(type default)
			)
			(layer "B.Fab")
		)
		(fp_line
			(start -0.12065 -0.2794)
			(end -0.12065 -0.3048)
			(stroke
				(width 0.1)
				(type default)
			)
			(layer "B.Fab")
		)
		(fp_line
			(start -0.12065 -0.3048)
			(end -0.67945 -0.3048)
			(stroke
				(width 0.1)
				(type default)
			)
			(layer "B.Fab")
		)
		(fp_line
			(start -0.67945 0.3048)
			(end -0.120396 0.3048)
			(stroke
				(width 0.1)
				(type default)
			)
			(layer "B.Fab")
		)
		(fp_line
			(start -0.67945 -0.3048)
			(end -0.67945 0.3048)
			(stroke
				(width 0.1)
				(type default)
			)
			(layer "B.Fab")
		)
		(pad "1" smd circle
			(at 0.40005 0)
			(size 0 0)
			(layers "B.Cu" "B.Mask" "B.Paste")
			(net "PD_CHJ_CPU1_DIMM_SAA")
		)
		(pad "2" smd circle
			(at -0.40005 0)
			(size 0 0)
			(layers "B.Cu" "B.Mask" "B.Paste")
			(net "GND")
		)
	)
)
